(kicad_pcb
	(version 20260206)
	(generator "pcbnew")
	(generator_version "10.0")
	(general
		(thickness 1.6)
		(legacy_teardrops no)
	)
	(paper "A4")
	(title_block
		(title "01162023_DA0F0TEBIF0_F0T_Expander_BD_F_brd_V02_OCP.brd")
		(comment 1 "Grand Teton / footprints 2496-2497 of 9728")
	)
	(layers
		(0 "F.Cu" signal "TOP")
		(4 "In1.Cu" signal "GND")
		(6 "In2.Cu" signal "VCC")
		(8 "In3.Cu" signal "VCC1")
		(10 "In4.Cu" signal "GND1")
		(12 "In5.Cu" signal "IN1")
		(14 "In6.Cu" signal "GND2")
		(16 "In7.Cu" signal "IN2")
		(18 "In8.Cu" signal "GND3")
		(20 "In9.Cu" signal "IN3")
		(22 "In10.Cu" signal "GND4")
		(24 "In11.Cu" signal "IN4")
		(26 "In12.Cu" signal "GND5")
		(28 "In13.Cu" signal "IN5")
		(30 "In14.Cu" signal "GND6")
		(32 "In15.Cu" signal "IN6")
		(34 "In16.Cu" signal "GND7")
		(2 "B.Cu" signal "BOTTOM")
		(9 "F.Adhes" user "F.Adhesive")
		(11 "B.Adhes" user "B.Adhesive")
		(13 "F.Paste" user "Package Geometry/Pastemask Top")
		(15 "B.Paste" user "Package Geometry/Pastemask Bottom")
		(5 "F.SilkS" user "Ref Des/Silkscreen Top")
		(7 "B.SilkS" user "Ref Des/Silkscreen Bottom")
		(1 "F.Mask" user "Board Geometry/Soldermask Top")
		(3 "B.Mask" user "Board Geometry/Soldermask Bottom")
		(17 "Dwgs.User" user "User.Drawings")
		(19 "Cmts.User" user "User.Comments")
		(21 "Eco1.User" user "User.Eco1")
		(23 "Eco2.User" user "User.Eco2")
		(25 "Edge.Cuts" user "Board Geometry/Outline")
		(27 "Margin" user)
		(31 "F.CrtYd" user "Package Geometry/Place Bound Top")
		(29 "B.CrtYd" user "Package Geometry/Place Bound Bottom")
		(35 "F.Fab" user "Ref Des/Assembly Top")
		(33 "B.Fab" user "Ref Des/Assembly Bottom")
	)
	(footprint ""
		(layer "F.Cu")
		(at 387.26491 -26.785062 180)
		(property "Reference" "J43"
			(at 4.476496 -11.077956 90)
			(unlocked yes)
			(layer "F.SilkS")
			(effects
				(font
					(size 0.7874 0.5842)
					(thickness 0.1524)
				)
			)
		)
		(property "Value" ""
			(at 0 0 180)
			(layer "F.Fab")
			(effects
				(font
					(size 1.27 1.27)
				)
			)
		)
		(duplicate_pad_numbers_are_jumpers no)
		(fp_line
			(start 3.150108 12.115038)
			(end 1.529334 12.115038)
			(stroke
				(width 0.1524)
				(type default)
			)
			(layer "F.SilkS")
		)
		(fp_line
			(start 3.074924 12.014962)
			(end 1.632204 12.014962)
			(stroke
				(width 0.1524)
				(type default)
			)
			(layer "F.SilkS")
		)
		(fp_line
			(start 1.632204 -12.014962)
			(end 3.074924 -12.014962)
			(stroke
				(width 0.1524)
				(type default)
			)
			(layer "F.SilkS")
		)
		(fp_line
			(start 1.529334 -12.115038)
			(end 3.150108 -12.115038)
			(stroke
				(width 0.1524)
				(type default)
			)
			(layer "F.SilkS")
		)
		(fp_line
			(start -1.529334 12.115038)
			(end -3.150108 12.115038)
			(stroke
				(width 0.1524)
				(type default)
			)
			(layer "F.SilkS")
		)
		(fp_line
			(start -1.632204 12.014962)
			(end -3.074924 12.014962)
			(stroke
				(width 0.1524)
				(type default)
			)
			(layer "F.SilkS")
		)
		(fp_line
			(start -3.074924 -12.014962)
			(end -1.632204 -12.014962)
			(stroke
				(width 0.1524)
				(type default)
			)
			(layer "F.SilkS")
		)
		(fp_line
			(start -3.150108 -12.115038)
			(end -1.529334 -12.115038)
			(stroke
				(width 0.1524)
				(type default)
			)
			(layer "F.SilkS")
		)
		(fp_poly
			(pts
				(xy 3.27279 -8.645398) (xy 3.695192 -9.913112) (xy 4.54025 -9.068054)
			)
			(stroke
				(width 0)
				(type default)
			)
			(fill yes)
			(layer "F.SilkS")
		)
		(fp_line
			(start 3.074924 12.014962)
			(end -3.074924 12.014962)
			(stroke
				(width 0.1)
				(type default)
			)
			(layer "F.Fab")
		)
		(fp_line
			(start 3.074924 -12.014962)
			(end 3.074924 12.014962)
			(stroke
				(width 0.1)
				(type default)
			)
			(layer "F.Fab")
		)
		(fp_line
			(start -3.074924 12.014962)
			(end -3.074924 -12.014962)
			(stroke
				(width 0.1)
				(type default)
			)
			(layer "F.Fab")
		)
		(fp_line
			(start -3.074924 -12.014962)
			(end 3.074924 -12.014962)
			(stroke
				(width 0.1)
				(type default)
			)
			(layer "F.Fab")
		)
		(fp_poly
			(pts
				(xy 3.348736 -7.994904) (xy 4.543806 -8.592566) (xy 4.543806 -7.397496)
			)
			(stroke
				(width 0)
				(type default)
			)
			(fill yes)
			(layer "F.Fab")
		)
		(pad "" np_thru_hole circle
			(at -1.75006 -9.815068 90)
			(size 1.1176 1.1176)
			(drill 1.1176)
			(layers "*.Cu" "*.Mask")
			(clearance 0.381)
			(thermal_gap 0.381)
		)
		(pad "" np_thru_hole circle
			(at 0 9.815068 90)
			(size 1.1176 1.1176)
			(drill 1.1176)
			(layers "*.Cu" "*.Mask")
			(clearance 0.381)
			(thermal_gap 0.381)
		)
		(pad "A1" smd rect
			(at 2.29997 -7.994904 90)
			(size 0.381 1.27)
			(layers "F.Cu" "F.Mask" "F.Paste")
			(net "GND")
		)
		(pad "A2" smd rect
			(at 2.29997 -7.394956 90)
			(size 0.381 1.27)
			(layers "F.Cu" "F.Mask" "F.Paste")
			(net "GND")
		)
		(pad "A3" smd rect
			(at 2.29997 -6.795008 90)
			(size 0.381 1.27)
			(layers "F.Cu" "F.Mask" "F.Paste")
			(net "GND")
		)
		(pad "A4" smd rect
			(at 2.29997 -6.19506 90)
			(size 0.381 1.27)
			(layers "F.Cu" "F.Mask" "F.Paste")
			(net "GND")
		)
		(pad "A5" smd rect
			(at 2.29997 -5.595112 90)
			(size 0.381 1.27)
			(layers "F.Cu" "F.Mask" "F.Paste")
			(net "GND")
		)
		(pad "A6" smd rect
			(at 2.29997 -4.99491 90)
			(size 0.381 1.27)
			(layers "F.Cu" "F.Mask" "F.Paste")
			(net "GND")
		)
		(pad "A7" smd rect
			(at 2.29997 -4.394962 90)
			(size 0.381 1.27)
			(layers "F.Cu" "F.Mask" "F.Paste")
			(net "SMB_ISO_SSD13_R_SCL")
		)
		(pad "A8" smd rect
			(at 2.29997 -3.795014 90)
			(size 0.381 1.27)
			(layers "F.Cu" "F.Mask" "F.Paste")
			(net "SMB_ISO_SSD13_R_SDA")
		)
		(pad "A9" smd rect
			(at 2.29997 -3.195066 90)
			(size 0.381 1.27)
			(layers "F.Cu" "F.Mask" "F.Paste")
			(net "RST_SMB_SSD13_ISO_R_N")
		)
		(pad "A10" smd rect
			(at 2.29997 -2.595118 90)
			(size 0.381 1.27)
			(layers "F.Cu" "F.Mask" "F.Paste")
			(net "SSD13_LED_ISO_R_N")
		)
		(pad "A11" smd rect
			(at 2.29997 -1.994916 90)
			(size 0.381 1.27)
			(layers "F.Cu" "F.Mask" "F.Paste")
			(net "PU_CLKREQ13")
		)
		(pad "A12" smd rect
			(at 2.29997 -1.394968 90)
			(size 0.381 1.27)
			(layers "F.Cu" "F.Mask" "F.Paste")
			(net "PRSNT_SSD13_N")
		)
		(pad "A13" smd rect
			(at 2.29997 -0.79502 90)
			(size 0.381 1.27)
			(layers "F.Cu" "F.Mask" "F.Paste")
			(net "GND")
		)
		(pad "A14" smd rect
			(at 2.29997 -0.195072 90)
			(size 0.381 1.27)
			(layers "F.Cu" "F.Mask" "F.Paste")
			(net "Net_8471")
		)
		(pad "A15" smd rect
			(at 2.29997 0.404876 90)
			(size 0.381 1.27)
			(layers "F.Cu" "F.Mask" "F.Paste")
			(net "Net_8470")
		)
		(pad "A16" smd rect
			(at 2.29997 1.005078 90)
			(size 0.381 1.27)
			(layers "F.Cu" "F.Mask" "F.Paste")
			(net "GND")
		)
		(pad "A17" smd rect
			(at 2.29997 1.605026 90)
			(size 0.381 1.27)
			(layers "F.Cu" "F.Mask" "F.Paste")
			(net "P5E_PEX3_STN2_RX_DN<40>")
		)
		(pad "A18" smd rect
			(at 2.29997 2.204974 90)
			(size 0.381 1.27)
			(layers "F.Cu" "F.Mask" "F.Paste")
			(net "P5E_PEX3_STN2_RX_DP<40>")
		)
		(pad "A19" smd rect
			(at 2.29997 2.804922 90)
			(size 0.381 1.27)
			(layers "F.Cu" "F.Mask" "F.Paste")
			(net "GND")
		)
		(pad "A20" smd rect
			(at 2.29997 3.405124 90)
			(size 0.381 1.27)
			(layers "F.Cu" "F.Mask" "F.Paste")
			(net "P5E_PEX3_STN2_RX_DN<41>")
		)
		(pad "A21" smd rect
			(at 2.29997 4.005072 90)
			(size 0.381 1.27)
			(layers "F.Cu" "F.Mask" "F.Paste")
			(net "P5E_PEX3_STN2_RX_DP<41>")
		)
		(pad "A22" smd rect
			(at 2.29997 4.60502 90)
			(size 0.381 1.27)
			(layers "F.Cu" "F.Mask" "F.Paste")
			(net "GND")
		)
		(pad "A23" smd rect
			(at 2.29997 5.204968 90)
			(size 0.381 1.27)
			(layers "F.Cu" "F.Mask" "F.Paste")
			(net "P5E_PEX3_STN2_RX_DN<42>")
		)
		(pad "A24" smd rect
			(at 2.29997 5.804916 90)
			(size 0.381 1.27)
			(layers "F.Cu" "F.Mask" "F.Paste")
			(net "P5E_PEX3_STN2_RX_DP<42>")
		)
		(pad "A25" smd rect
			(at 2.29997 6.405118 90)
			(size 0.381 1.27)
			(layers "F.Cu" "F.Mask" "F.Paste")
			(net "GND")
		)
		(pad "A26" smd rect
			(at 2.29997 7.005066 90)
			(size 0.381 1.27)
			(layers "F.Cu" "F.Mask" "F.Paste")
			(net "P5E_PEX3_STN2_RX_DN<43>")
		)
		(pad "A27" smd rect
			(at 2.29997 7.605014 90)
			(size 0.381 1.27)
			(layers "F.Cu" "F.Mask" "F.Paste")
			(net "P5E_PEX3_STN2_RX_DP<43>")
		)
		(pad "A28" smd rect
			(at 2.29997 8.204962 90)
			(size 0.381 1.27)
			(layers "F.Cu" "F.Mask" "F.Paste")
			(net "GND")
		)
		(pad "B1" smd rect
			(at -2.29997 -7.994904 90)
			(size 0.381 1.27)
			(layers "F.Cu" "F.Mask" "F.Paste")
			(net "P12V_SSD13")
		)
		(pad "B2" smd rect
			(at -2.29997 -7.394956 90)
			(size 0.381 1.27)
			(layers "F.Cu" "F.Mask" "F.Paste")
			(net "P12V_SSD13")
		)
		(pad "B3" smd rect
			(at -2.29997 -6.795008 90)
			(size 0.381 1.27)
			(layers "F.Cu" "F.Mask" "F.Paste")
			(net "P12V_SSD13")
		)
		(pad "B4" smd rect
			(at -2.29997 -6.19506 90)
			(size 0.381 1.27)
			(layers "F.Cu" "F.Mask" "F.Paste")
			(net "P12V_SSD13")
		)
		(pad "B5" smd rect
			(at -2.29997 -5.595112 90)
			(size 0.381 1.27)
			(layers "F.Cu" "F.Mask" "F.Paste")
			(net "P12V_SSD13")
		)
		(pad "B6" smd rect
			(at -2.29997 -4.99491 90)
			(size 0.381 1.27)
			(layers "F.Cu" "F.Mask" "F.Paste")
			(net "P12V_SSD13")
		)
		(pad "B7" smd rect
			(at -2.29997 -4.394962 90)
			(size 0.381 1.27)
			(layers "F.Cu" "F.Mask" "F.Paste")
			(net "Net_8472")
		)
		(pad "B8" smd rect
			(at -2.29997 -3.795014 90)
			(size 0.381 1.27)
			(layers "F.Cu" "F.Mask" "F.Paste")
			(net "Net_8469")
		)
		(pad "B9" smd rect
			(at -2.29997 -3.195066 90)
			(size 0.381 1.27)
			(layers "F.Cu" "F.Mask" "F.Paste")
			(net "DUALPORT_N_SSD13")
		)
		(pad "B10" smd rect
			(at -2.29997 -2.595118 90)
			(size 0.381 1.27)
			(layers "F.Cu" "F.Mask" "F.Paste")
			(net "RST_SSD13_PERST_R_N")
		)
		(pad "B11" smd rect
			(at -2.29997 -1.994916 90)
			(size 0.381 1.27)
			(layers "F.Cu" "F.Mask" "F.Paste")
			(net "P3V3_SSD13")
		)
		(pad "B12" smd rect
			(at -2.29997 -1.394968 90)
			(size 0.381 1.27)
			(layers "F.Cu" "F.Mask" "F.Paste")
			(net "SSD13_PWRDIS_R")
		)
		(pad "B13" smd rect
			(at -2.29997 -0.79502 90)
			(size 0.381 1.27)
			(layers "F.Cu" "F.Mask" "F.Paste")
			(net "GND")
		)
		(pad "B14" smd rect
			(at -2.29997 -0.195072 90)
			(size 0.381 1.27)
			(layers "F.Cu" "F.Mask" "F.Paste")
			(net "CLK_100M_DB800ZL_SSD13_R_DN")
		)
		(pad "B15" smd rect
			(at -2.29997 0.404876 90)
			(size 0.381 1.27)
			(layers "F.Cu" "F.Mask" "F.Paste")
			(net "CLK_100M_DB800ZL_SSD13_R_DP")
		)
		(pad "B16" smd rect
			(at -2.29997 1.005078 90)
			(size 0.381 1.27)
			(layers "F.Cu" "F.Mask" "F.Paste")
			(net "GND")
		)
		(pad "B17" smd rect
			(at -2.29997 1.605026 90)
			(size 0.381 1.27)
			(layers "F.Cu" "F.Mask" "F.Paste")
			(net "P5E_PEX3_STN2_TX_C_DN<40>")
		)
		(pad "B18" smd rect
			(at -2.29997 2.204974 90)
			(size 0.381 1.27)
			(layers "F.Cu" "F.Mask" "F.Paste")
			(net "P5E_PEX3_STN2_TX_C_DP<40>")
		)
		(pad "B19" smd rect
			(at -2.29997 2.804922 90)
			(size 0.381 1.27)
			(layers "F.Cu" "F.Mask" "F.Paste")
			(net "GND")
		)
		(pad "B20" smd rect
			(at -2.29997 3.405124 90)
			(size 0.381 1.27)
			(layers "F.Cu" "F.Mask" "F.Paste")
			(net "P5E_PEX3_STN2_TX_C_DN<41>")
		)
		(pad "B21" smd rect
			(at -2.29997 4.005072 90)
			(size 0.381 1.27)
			(layers "F.Cu" "F.Mask" "F.Paste")
			(net "P5E_PEX3_STN2_TX_C_DP<41>")
		)
		(pad "B22" smd rect
			(at -2.29997 4.60502 90)
			(size 0.381 1.27)
			(layers "F.Cu" "F.Mask" "F.Paste")
			(net "GND")
		)
		(pad "B23" smd rect
			(at -2.29997 5.204968 90)
			(size 0.381 1.27)
			(layers "F.Cu" "F.Mask" "F.Paste")
			(net "P5E_PEX3_STN2_TX_C_DN<42>")
		)
		(pad "B24" smd rect
			(at -2.29997 5.804916 90)
			(size 0.381 1.27)
			(layers "F.Cu" "F.Mask" "F.Paste")
			(net "P5E_PEX3_STN2_TX_C_DP<42>")
		)
		(pad "B25" smd rect
			(at -2.29997 6.405118 90)
			(size 0.381 1.27)
			(layers "F.Cu" "F.Mask" "F.Paste")
			(net "GND")
		)
		(pad "B26" smd rect
			(at -2.29997 7.005066 90)
			(size 0.381 1.27)
			(layers "F.Cu" "F.Mask" "F.Paste")
			(net "P5E_PEX3_STN2_TX_C_DN<43>")
		)
		(pad "B27" smd rect
			(at -2.29997 7.605014 90)
			(size 0.381 1.27)
			(layers "F.Cu" "F.Mask" "F.Paste")
			(net "P5E_PEX3_STN2_TX_C_DP<43>")
		)
		(pad "B28" smd rect
			(at -2.29997 8.204962 90)
			(size 0.381 1.27)
			(layers "F.Cu" "F.Mask" "F.Paste")
			(net "GND")
		)
		(pad "G1" thru_hole oval
			(at 0 -11.364976 90)
			(size 1.6256 3.4798)
			(drill oval 1.1176 2.4638)
			(layers "*.Cu" "*.Mask")
			(remove_unused_layers no)
			(net "GND")
			(clearance 0.127)
			(thermal_gap 0.127)
		)
		(pad "G2" thru_hole oval
			(at 0 11.364976 90)
			(size 1.6256 3.4798)
			(drill oval 1.1176 2.4638)
			(layers "*.Cu" "*.Mask")
			(remove_unused_layers no)
			(net "GND")
			(clearance 0.127)
			(thermal_gap 0.127)
		)
		(zone
			(layer "F.Cu")
			(hatch none 0.5)
			(connect_pads
				(clearance 0)
			)
			(min_thickness 0.25)
			(keepout
				(tracks not_allowed)
				(vias allowed)
				(pads allowed)
				(copperpour not_allowed)
				(footprints allowed)
			)
			(placement
				(enabled no)
				(sheetname "")
			)
			(fill
				(thermal_gap 0.5)
				(thermal_bridge_width 0.5)
				(island_removal_mode 0)
			)
			(polygon
				(pts
					(xy 388.644892 -38.850062) (xy 385.894834 -38.850062) (xy 385.894834 -35.900106) (xy 388.644892 -35.900106)
				)
			)
		)
		(zone
			(layer "F.Cu")
			(hatch none 0.5)
			(connect_pads
				(clearance 0)
			)
			(min_thickness 0.25)
			(keepout
				(tracks not_allowed)
				(vias allowed)
				(pads allowed)
				(copperpour not_allowed)
				(footprints allowed)
			)
			(placement
				(enabled no)
				(sheetname "")
			)
			(fill
				(thermal_gap 0.5)
				(thermal_bridge_width 0.5)
				(island_removal_mode 0)
			)
			(polygon
				(pts
					(xy 389.714994 -17.670018) (xy 385.884928 -17.670018) (xy 385.884928 -14.720062) (xy 389.714994 -14.720062)
				)
			)
		)
		(zone
			(layers "F.Cu" "B.Cu" "In1.Cu" "In2.Cu" "In3.Cu" "In4.Cu" "In5.Cu" "In6.Cu"
				"In7.Cu" "In8.Cu" "In9.Cu" "In10.Cu" "In11.Cu" "In12.Cu" "In13.Cu" "In14.Cu"
				"In15.Cu" "In16.Cu"
			)
			(hatch none 0.5)
			(connect_pads
				(clearance 0)
			)
			(min_thickness 0.25)
			(keepout
				(tracks not_allowed)
				(vias allowed)
				(pads allowed)
				(copperpour not_allowed)
				(footprints allowed)
			)
			(placement
				(enabled no)
				(sheetname "")
			)
			(fill
				(thermal_gap 0.5)
				(thermal_bridge_width 0.5)
				(island_removal_mode 0)
			)
			(polygon
				(pts
					(arc
						(start 388.23011 -36.60013)
						(mid 386.29971 -36.60013)
						(end 388.23011 -36.60013)
					)
				)
			)
		)
		(zone
			(layers "F.Cu" "B.Cu" "In1.Cu" "In2.Cu" "In3.Cu" "In4.Cu" "In5.Cu" "In6.Cu"
				"In7.Cu" "In8.Cu" "In9.Cu" "In10.Cu" "In11.Cu" "In12.Cu" "In13.Cu" "In14.Cu"
				"In15.Cu" "In16.Cu"
			)
			(hatch none 0.5)
			(connect_pads
				(clearance 0)
			)
			(min_thickness 0.25)
			(keepout
				(tracks not_allowed)
				(vias allowed)
				(pads allowed)
				(copperpour not_allowed)
				(footprints allowed)
			)
			(placement
				(enabled no)
				(sheetname "")
			)
			(fill
				(thermal_gap 0.5)
				(thermal_bridge_width 0.5)
				(island_removal_mode 0)
			)
			(polygon
				(pts
					(arc
						(start 389.98017 -16.969994)
						(mid 388.04977 -16.969994)
						(end 389.98017 -16.969994)
					)
				)
			)
		)
	)
	(footprint ""
		(layer "F.Cu")
		(at 368.038634 -44.341542 90)
		(property "Reference" "C335"
			(at 0 0 90)
			(layer "F.SilkS")
			(hide yes)
			(effects
				(font
					(size 1.27 1.27)
				)
			)
		)
		(property "Value" ""
			(at 0 0 90)
			(layer "F.Fab")
			(effects
				(font
					(size 1.27 1.27)
				)
			)
		)
		(duplicate_pad_numbers_are_jumpers no)
		(fp_line
			(start 0.7874 -0.4064)
			(end 0.7874 0.4064)
			(stroke
				(width 0.1524)
				(type default)
			)
			(layer "F.SilkS")
		)
		(fp_line
			(start -0.7874 -0.4064)
			(end 0.7874 -0.4064)
			(stroke
				(width 0.1524)
				(type default)
			)
			(layer "F.SilkS")
		)
		(fp_line
			(start 0.7874 0.4064)
			(end -0.7874 0.4064)
			(stroke
				(width 0.1524)
				(type default)
			)
			(layer "F.SilkS")
		)
		(fp_line
			(start -0.7874 0.4064)
			(end -0.7874 -0.4064)
			(stroke
				(width 0.1524)
				(type default)
			)
			(layer "F.SilkS")
		)
		(fp_line
			(start -0.12065 -0.305054)
			(end -0.12065 -0.2794)
			(stroke
				(width 0.1)
				(type default)
			)
			(layer "F.Fab")
		)
		(fp_line
			(start -0.67945 -0.305054)
			(end -0.12065 -0.305054)
			(stroke
				(width 0.1)
				(type default)
			)
			(layer "F.Fab")
		)
		(fp_line
			(start 0.67945 -0.3048)
			(end 0.67945 0.3048)
			(stroke
				(width 0.1)
				(type default)
			)
			(layer "F.Fab")
		)
		(fp_line
			(start 0.12065 -0.3048)
			(end 0.67945 -0.3048)
			(stroke
				(width 0.1)
				(type default)
			)
			(layer "F.Fab")
		)
		(fp_line
			(start 0.12065 -0.2794)
			(end 0.12065 -0.3048)
			(stroke
				(width 0.1)
				(type default)
			)
			(layer "F.Fab")
		)
		(fp_line
			(start -0.12065 -0.2794)
			(end 0.12065 -0.2794)
			(stroke
				(width 0.1)
				(type default)
			)
			(layer "F.Fab")
		)
		(fp_line
			(start 0.120396 0.2794)
			(end -0.12065 0.2794)
			(stroke
				(width 0.1)
				(type default)
			)
			(layer "F.Fab")
		)
		(fp_line
			(start -0.12065 0.2794)
			(end -0.12065 0.3048)
			(stroke
				(width 0.1)
				(type default)
			)
			(layer "F.Fab")
		)
		(fp_line
			(start 0.67945 0.3048)
			(end 0.120396 0.3048)
			(stroke
				(width 0.1)
				(type default)
			)
			(layer "F.Fab")
		)
		(fp_line
			(start 0.120396 0.3048)
			(end 0.120396 0.2794)
			(stroke
				(width 0.1)
				(type default)
			)
			(layer "F.Fab")
		)
		(fp_line
			(start -0.12065 0.3048)
			(end -0.67945 0.3048)
			(stroke
				(width 0.1)
				(type default)
			)
			(layer "F.Fab")
		)
		(fp_line
			(start -0.67945 0.3048)
			(end -0.67945 -0.305054)
			(stroke
				(width 0.1)
				(type default)
			)
			(layer "F.Fab")
		)
		(pad "1" smd circle
			(at -0.40005 0 90)
			(size 0 0)
			(layers "F.Cu" "F.Mask" "F.Paste")
			(net "P12V_SSD12_VIN_P")
		)
		(pad "2" smd circle
			(at 0.40005 0 90)
			(size 0 0)
			(layers "F.Cu" "F.Mask" "F.Paste")
			(net "P12V_SSD12_VIN_N")
		)
	)
)
